(kicad_pcb
	(version 20260206)
	(generator "pcbnew")
	(generator_version "10.0")
	(general
		(thickness 1.6)
		(legacy_teardrops no)
	)
	(paper "A4")
	(title_block
		(title "Bryce Canyon_SCC_16316-1_OCP.brd")
		(comment 1 "Bryce Canyon / footprints 1456-1463 of 1561")
	)
	(layers
		(0 "F.Cu" signal "TOP")
		(4 "In1.Cu" signal "L2GND")
		(6 "In2.Cu" signal "L3")
		(8 "In3.Cu" signal "L4VCC")
		(10 "In4.Cu" signal "L5VCC")
		(12 "In5.Cu" signal "L6")
		(14 "In6.Cu" signal "L7GND")
		(2 "B.Cu" signal "BOTTOM")
		(9 "F.Adhes" user "F.Adhesive")
		(11 "B.Adhes" user "B.Adhesive")
		(13 "F.Paste" user "Package Geometry/Pastemask Top")
		(15 "B.Paste" user "Package Geometry/Pastemask Bottom")
		(5 "F.SilkS" user "Ref Des/Silkscreen Top")
		(7 "B.SilkS" user "Ref Des/Silkscreen Bottom")
		(1 "F.Mask" user "Board Geometry/Soldermask Top")
		(3 "B.Mask" user "Board Geometry/Soldermask Bottom")
		(17 "Dwgs.User" user "User.Drawings")
		(19 "Cmts.User" user "User.Comments")
		(21 "Eco1.User" user "User.Eco1")
		(23 "Eco2.User" user "User.Eco2")
		(25 "Edge.Cuts" user "Board Geometry/Outline")
		(27 "Margin" user)
		(31 "F.CrtYd" user "Package Geometry/Place Bound Top")
		(29 "B.CrtYd" user "Package Geometry/Place Bound Bottom")
		(35 "F.Fab" user "Ref Des/Assembly Top")
		(33 "B.Fab" user "Ref Des/Assembly Bottom")
	)
	(footprint ""
		(layer "B.Cu")
		(at 203.3524 -45.80382)
		(property "Reference" "C346"
			(at 0 0 0)
			(layer "B.SilkS")
			(hide yes)
			(effects
				(font
					(size 1.27 1.27)
				)
				(justify mirror)
			)
		)
		(property "Value" "SCD01U25V2KX-3GP"
			(at -1.1811 -2.7051 0)
			(unlocked yes)
			(layer "B.Fab")
			(hide yes)
			(effects
				(font
					(size 1.016 1.016)
					(thickness 0.1524)
				)
				(justify mirror)
			)
		)
		(property "Device Type" "C402H22"
			(at -1.1811 -4.2291 0)
			(unlocked yes)
			(layer "B.Fab")
			(hide yes)
			(effects
				(font
					(size 1.016 1.016)
					(thickness 0.1524)
				)
				(justify mirror)
			)
		)
		(duplicate_pad_numbers_are_jumpers no)
		(fp_rect
			(start 0.4318 0.9525)
			(end -0.4318 -0.9525)
			(stroke
				(width 0)
				(type default)
			)
			(fill no)
			(layer "B.CrtYd")
		)
		(fp_rect
			(start 0.4318 0.9525)
			(end -0.4318 -0.9525)
			(stroke
				(width 0)
				(type default)
			)
			(fill no)
			(layer "B.Fab")
		)
		(pad "1" smd custom
			(at 0 -0.4445 180)
			(size 0.1524 0.1524)
			(layers "B.Cu" "B.Mask" "B.Paste")
			(net "GND")
			(options
				(clearance outline)
				(anchor circle)
			)
			(primitives
				(gr_poly
					(pts
						(arc
							(start 0.3048 0.2032)
							(mid 0.275042 0.275042)
							(end 0.2032 0.3048)
						)
						(arc
							(start -0.2032 0.3048)
							(mid -0.275042 0.275042)
							(end -0.3048 0.2032)
						)
						(arc
							(start -0.3048 -0.2032)
							(mid -0.275042 -0.275042)
							(end -0.2032 -0.3048)
						)
						(arc
							(start 0.2032 -0.3048)
							(mid 0.275042 -0.275042)
							(end 0.3048 -0.2032)
						)
					)
					(width 0)
					(fill yes)
				)
			)
		)
		(pad "2" smd custom
			(at 0 0.4445 180)
			(size 0.1524 0.1524)
			(layers "B.Cu" "B.Mask" "B.Paste")
			(net "P1V8_C")
			(options
				(clearance outline)
				(anchor circle)
			)
			(primitives
				(gr_poly
					(pts
						(arc
							(start 0.3048 0.2032)
							(mid 0.275042 0.275042)
							(end 0.2032 0.3048)
						)
						(arc
							(start -0.2032 0.3048)
							(mid -0.275042 0.275042)
							(end -0.3048 0.2032)
						)
						(arc
							(start -0.3048 -0.2032)
							(mid -0.275042 -0.275042)
							(end -0.2032 -0.3048)
						)
						(arc
							(start 0.2032 -0.3048)
							(mid 0.275042 -0.275042)
							(end 0.3048 -0.2032)
						)
					)
					(width 0)
					(fill yes)
				)
			)
		)
	)
	(footprint ""
		(layer "B.Cu")
		(at 160.782 -16.256)
		(property "Reference" "R81"
			(at 0 0 0)
			(layer "B.SilkS")
			(hide yes)
			(effects
				(font
					(size 1.27 1.27)
				)
				(justify mirror)
			)
		)
		(property "Value" "10KR2F-2-GP"
			(at -0.064008 -3.993896 0)
			(unlocked yes)
			(layer "B.Fab")
			(hide yes)
			(effects
				(font
					(size 1.016 1.016)
					(thickness 0.1524)
				)
				(justify mirror)
			)
		)
		(property "Device Type" "R402H16"
			(at -0.064008 -5.517896 0)
			(unlocked yes)
			(layer "B.Fab")
			(hide yes)
			(effects
				(font
					(size 1.016 1.016)
					(thickness 0.1524)
				)
				(justify mirror)
			)
		)
		(duplicate_pad_numbers_are_jumpers no)
		(fp_line
			(start -0.508 -0.9398)
			(end 0.508 -0.9398)
			(stroke
				(width 0.1524)
				(type default)
			)
			(layer "B.SilkS")
		)
		(fp_line
			(start 0.508 -0.9398)
			(end 0.508 0.9398)
			(stroke
				(width 0.1524)
				(type default)
			)
			(layer "B.SilkS")
		)
		(fp_rect
			(start 0.508 0.9398)
			(end -0.508 -0.9398)
			(stroke
				(width 0)
				(type default)
			)
			(fill no)
			(layer "B.CrtYd")
		)
		(fp_rect
			(start 0.508 0.9398)
			(end -0.508 -0.9398)
			(stroke
				(width 0)
				(type default)
			)
			(fill no)
			(layer "B.Fab")
		)
		(pad "1" smd custom
			(at 0 -0.4445 180)
			(size 0.1397 0.1397)
			(layers "B.Cu" "B.Mask" "B.Paste")
			(net "P12V_STBY_SCC")
			(options
				(clearance outline)
				(anchor circle)
			)
			(primitives
				(gr_poly
					(pts
						(arc
							(start -0.1778 0.2794)
							(mid -0.249642 0.249642)
							(end -0.2794 0.1778)
						)
						(arc
							(start -0.2794 -0.1778)
							(mid -0.249642 -0.249642)
							(end -0.1778 -0.2794)
						)
						(arc
							(start 0.1778 -0.2794)
							(mid 0.249642 -0.249642)
							(end 0.2794 -0.1778)
						)
						(arc
							(start 0.2794 0.1778)
							(mid 0.249642 0.249642)
							(end 0.1778 0.2794)
						)
					)
					(width 0)
					(fill yes)
				)
			)
		)
		(pad "2" smd custom
			(at 0 0.4445 180)
			(size 0.1397 0.1397)
			(layers "B.Cu" "B.Mask" "B.Paste")
			(net "LS_EN_N")
			(options
				(clearance outline)
				(anchor circle)
			)
			(primitives
				(gr_poly
					(pts
						(arc
							(start -0.1778 0.2794)
							(mid -0.249642 0.249642)
							(end -0.2794 0.1778)
						)
						(arc
							(start -0.2794 -0.1778)
							(mid -0.249642 -0.249642)
							(end -0.1778 -0.2794)
						)
						(arc
							(start 0.1778 -0.2794)
							(mid 0.249642 -0.249642)
							(end 0.2794 -0.1778)
						)
						(arc
							(start 0.2794 0.1778)
							(mid 0.249642 0.249642)
							(end 0.1778 0.2794)
						)
					)
					(width 0)
					(fill yes)
				)
			)
		)
	)
	(footprint ""
		(layer "B.Cu")
		(at 114.681 -61.488066)
		(property "Reference" "C222"
			(at 0 0 0)
			(layer "B.SilkS")
			(hide yes)
			(effects
				(font
					(size 1.27 1.27)
				)
				(justify mirror)
			)
		)
		(property "Value" "SCD1U16V2KX-3GP"
			(at -1.1811 -2.7051 0)
			(unlocked yes)
			(layer "B.Fab")
			(hide yes)
			(effects
				(font
					(size 1.016 1.016)
					(thickness 0.1524)
				)
				(justify mirror)
			)
		)
		(property "Device Type" "C402H22"
			(at -1.1811 -4.2291 0)
			(unlocked yes)
			(layer "B.Fab")
			(hide yes)
			(effects
				(font
					(size 1.016 1.016)
					(thickness 0.1524)
				)
				(justify mirror)
			)
		)
		(duplicate_pad_numbers_are_jumpers no)
		(fp_rect
			(start 0.4318 0.9525)
			(end -0.4318 -0.9525)
			(stroke
				(width 0)
				(type default)
			)
			(fill no)
			(layer "B.CrtYd")
		)
		(fp_rect
			(start 0.4318 0.9525)
			(end -0.4318 -0.9525)
			(stroke
				(width 0)
				(type default)
			)
			(fill no)
			(layer "B.Fab")
		)
		(pad "1" smd custom
			(at 0 -0.4445 180)
			(size 0.1524 0.1524)
			(layers "B.Cu" "B.Mask" "B.Paste")
			(net "GB_VDDH")
			(options
				(clearance outline)
				(anchor circle)
			)
			(primitives
				(gr_poly
					(pts
						(arc
							(start 0.3048 0.2032)
							(mid 0.275042 0.275042)
							(end 0.2032 0.3048)
						)
						(arc
							(start -0.2032 0.3048)
							(mid -0.275042 0.275042)
							(end -0.3048 0.2032)
						)
						(arc
							(start -0.3048 -0.2032)
							(mid -0.275042 -0.275042)
							(end -0.2032 -0.3048)
						)
						(arc
							(start 0.2032 -0.3048)
							(mid 0.275042 -0.275042)
							(end 0.3048 -0.2032)
						)
					)
					(width 0)
					(fill yes)
				)
			)
		)
		(pad "2" smd custom
			(at 0 0.4445 180)
			(size 0.1524 0.1524)
			(layers "B.Cu" "B.Mask" "B.Paste")
			(net "GND")
			(options
				(clearance outline)
				(anchor circle)
			)
			(primitives
				(gr_poly
					(pts
						(arc
							(start 0.3048 0.2032)
							(mid 0.275042 0.275042)
							(end 0.2032 0.3048)
						)
						(arc
							(start -0.2032 0.3048)
							(mid -0.275042 0.275042)
							(end -0.3048 0.2032)
						)
						(arc
							(start -0.3048 -0.2032)
							(mid -0.275042 -0.275042)
							(end -0.2032 -0.3048)
						)
						(arc
							(start 0.2032 -0.3048)
							(mid 0.275042 -0.275042)
							(end 0.3048 -0.2032)
						)
					)
					(width 0)
					(fill yes)
				)
			)
		)
	)
	(footprint ""
		(layer "B.Cu")
		(at 163.2966 -37.7952 90)
		(property "Reference" "C374"
			(at 0 0 90)
			(layer "B.SilkS")
			(hide yes)
			(effects
				(font
					(size 1.27 1.27)
				)
				(justify mirror)
			)
		)
		(property "Value" "SCD1U16V2KX-3GP"
			(at -1.1811 -2.7051 90)
			(unlocked yes)
			(layer "B.Fab")
			(hide yes)
			(effects
				(font
					(size 1.016 1.016)
					(thickness 0.1524)
				)
				(justify mirror)
			)
		)
		(property "Device Type" "C402H22"
			(at -1.1811 -4.2291 90)
			(unlocked yes)
			(layer "B.Fab")
			(hide yes)
			(effects
				(font
					(size 1.016 1.016)
					(thickness 0.1524)
				)
				(justify mirror)
			)
		)
		(duplicate_pad_numbers_are_jumpers no)
		(fp_rect
			(start 0.4318 0.9525)
			(end -0.4318 -0.9525)
			(stroke
				(width 0)
				(type default)
			)
			(fill no)
			(layer "B.CrtYd")
		)
		(fp_rect
			(start 0.4318 0.9525)
			(end -0.4318 -0.9525)
			(stroke
				(width 0)
				(type default)
			)
			(fill no)
			(layer "B.Fab")
		)
		(pad "1" smd custom
			(at 0 -0.4445 270)
			(size 0.1524 0.1524)
			(layers "B.Cu" "B.Mask" "B.Paste")
			(net "SAS0_VDDH")
			(options
				(clearance outline)
				(anchor circle)
			)
			(primitives
				(gr_poly
					(pts
						(arc
							(start 0.3048 0.2032)
							(mid 0.275042 0.275042)
							(end 0.2032 0.3048)
						)
						(arc
							(start -0.2032 0.3048)
							(mid -0.275042 0.275042)
							(end -0.3048 0.2032)
						)
						(arc
							(start -0.3048 -0.2032)
							(mid -0.275042 -0.275042)
							(end -0.2032 -0.3048)
						)
						(arc
							(start 0.2032 -0.3048)
							(mid 0.275042 -0.275042)
							(end 0.3048 -0.2032)
						)
					)
					(width 0)
					(fill yes)
				)
			)
		)
		(pad "2" smd custom
			(at 0 0.4445 270)
			(size 0.1524 0.1524)
			(layers "B.Cu" "B.Mask" "B.Paste")
			(net "GND")
			(options
				(clearance outline)
				(anchor circle)
			)
			(primitives
				(gr_poly
					(pts
						(arc
							(start 0.3048 0.2032)
							(mid 0.275042 0.275042)
							(end 0.2032 0.3048)
						)
						(arc
							(start -0.2032 0.3048)
							(mid -0.275042 0.275042)
							(end -0.3048 0.2032)
						)
						(arc
							(start -0.3048 -0.2032)
							(mid -0.275042 -0.275042)
							(end -0.2032 -0.3048)
						)
						(arc
							(start 0.2032 -0.3048)
							(mid 0.275042 -0.275042)
							(end 0.3048 -0.2032)
						)
					)
					(width 0)
					(fill yes)
				)
			)
		)
	)
	(footprint ""
		(layer "B.Cu")
		(at 163.068 -61.976 -90)
		(property "Reference" "C368"
			(at 0 0 90)
			(layer "B.SilkS")
			(hide yes)
			(effects
				(font
					(size 1.27 1.27)
				)
				(justify mirror)
			)
		)
		(property "Value" "SC10U6D3V5KX-4GP"
			(at 0.0762 -6.1214 270)
			(unlocked yes)
			(layer "B.Fab")
			(hide yes)
			(effects
				(font
					(size 1.016 1.016)
					(thickness 0.1524)
				)
				(justify mirror)
			)
		)
		(property "Device Type" "C805H58"
			(at 0.0762 -8.1534 270)
			(unlocked yes)
			(layer "B.Fab")
			(hide yes)
			(effects
				(font
					(size 1.016 1.016)
					(thickness 0.1524)
				)
				(justify mirror)
			)
		)
		(duplicate_pad_numbers_are_jumpers no)
		(fp_line
			(start -0.635 0)
			(end 0.635 0)
			(stroke
				(width 0.508)
				(type default)
			)
			(layer "B.SilkS")
		)
		(fp_rect
			(start 0.9652 1.778)
			(end -0.9652 -1.778)
			(stroke
				(width 0)
				(type default)
			)
			(fill no)
			(layer "B.CrtYd")
		)
		(fp_poly
			(pts
				(xy 0.9652 -1.778) (xy -0.9652 -1.778) (xy -0.9652 1.778) (xy 0.9652 1.778)
			)
			(stroke
				(width 0)
				(type default)
			)
			(fill no)
			(layer "B.Fab")
		)
		(pad "1" smd rect
			(at 0 -0.9652 90)
			(size 1.397 1.143)
			(layers "B.Cu" "B.Mask" "B.Paste")
			(net "VDDA_SAS_REF_CLK")
		)
		(pad "2" smd rect
			(at 0 0.9652 90)
			(size 1.397 1.143)
			(layers "B.Cu" "B.Mask" "B.Paste")
			(net "GND")
		)
	)
	(footprint ""
		(layer "B.Cu")
		(at 157.740604 -60.617608 90)
		(property "Reference" "C361"
			(at 0 0 90)
			(layer "B.SilkS")
			(hide yes)
			(effects
				(font
					(size 1.27 1.27)
				)
				(justify mirror)
			)
		)
		(property "Value" "SC1U16V2KX-7-GP"
			(at -1.7526 -1.6002 90)
			(unlocked yes)
			(layer "B.Fab")
			(hide yes)
			(effects
				(font
					(size 1.016 1.016)
					(thickness 0.1524)
				)
				(justify mirror)
			)
		)
		(property "Device Type" "C402-TO0D2H24"
			(at -1.7526 -3.1242 90)
			(unlocked yes)
			(layer "B.Fab")
			(hide yes)
			(effects
				(font
					(size 1.016 1.016)
					(thickness 0.1524)
				)
				(justify mirror)
			)
		)
		(duplicate_pad_numbers_are_jumpers no)
		(fp_rect
			(start 0.4826 0.889)
			(end -0.4826 -0.889)
			(stroke
				(width 0)
				(type default)
			)
			(fill no)
			(layer "B.CrtYd")
		)
		(fp_rect
			(start 0.4826 0.889)
			(end -0.4826 -0.889)
			(stroke
				(width 0)
				(type default)
			)
			(fill no)
			(layer "B.Fab")
		)
		(pad "1" smd custom
			(at 0 -0.4572 270)
			(size 0.1524 0.1524)
			(layers "B.Cu" "B.Mask" "B.Paste")
			(net "SHELL_PLL_VDD")
			(options
				(clearance outline)
				(anchor circle)
			)
			(primitives
				(gr_poly
					(pts
						(arc
							(start -0.254 -0.3048)
							(mid -0.325842 -0.275042)
							(end -0.3556 -0.2032)
						)
						(arc
							(start -0.3556 0.2032)
							(mid -0.325842 0.275042)
							(end -0.254 0.3048)
						)
						(arc
							(start 0.254 0.3048)
							(mid 0.325842 0.275042)
							(end 0.3556 0.2032)
						)
						(arc
							(start 0.3556 -0.2032)
							(mid 0.325842 -0.275042)
							(end 0.254 -0.3048)
						)
					)
					(width 0)
					(fill yes)
				)
			)
		)
		(pad "2" smd custom
			(at 0 0.4572 270)
			(size 0.1524 0.1524)
			(layers "B.Cu" "B.Mask" "B.Paste")
			(net "GND")
			(options
				(clearance outline)
				(anchor circle)
			)
			(primitives
				(gr_poly
					(pts
						(arc
							(start -0.254 -0.3048)
							(mid -0.325842 -0.275042)
							(end -0.3556 -0.2032)
						)
						(arc
							(start -0.3556 0.2032)
							(mid -0.325842 0.275042)
							(end -0.254 0.3048)
						)
						(arc
							(start 0.254 0.3048)
							(mid 0.325842 0.275042)
							(end 0.3556 0.2032)
						)
						(arc
							(start 0.3556 -0.2032)
							(mid 0.325842 -0.275042)
							(end 0.254 -0.3048)
						)
					)
					(width 0)
					(fill yes)
				)
			)
		)
	)
	(footprint ""
		(layer "B.Cu")
		(at 131.6863 -120.904 -90)
		(property "Reference" "R10"
			(at 0 0 90)
			(layer "B.SilkS")
			(hide yes)
			(effects
				(font
					(size 1.27 1.27)
				)
				(justify mirror)
			)
		)
		(property "Value" "1KR2F-3-GP"
			(at -0.064008 -3.993896 270)
			(unlocked yes)
			(layer "B.Fab")
			(hide yes)
			(effects
				(font
					(size 1.016 1.016)
					(thickness 0.1524)
				)
				(justify mirror)
			)
		)
		(property "Device Type" "R402H16"
			(at -0.064008 -5.517896 270)
			(unlocked yes)
			(layer "B.Fab")
			(hide yes)
			(effects
				(font
					(size 1.016 1.016)
					(thickness 0.1524)
				)
				(justify mirror)
			)
		)
		(duplicate_pad_numbers_are_jumpers no)
		(fp_line
			(start -0.508 -0.9398)
			(end 0.508 -0.9398)
			(stroke
				(width 0.1524)
				(type default)
			)
			(layer "B.SilkS")
		)
		(fp_line
			(start 0.508 -0.9398)
			(end 0.508 0.9398)
			(stroke
				(width 0.1524)
				(type default)
			)
			(layer "B.SilkS")
		)
		(fp_rect
			(start 0.508 0.9398)
			(end -0.508 -0.9398)
			(stroke
				(width 0)
				(type default)
			)
			(fill no)
			(layer "B.CrtYd")
		)
		(fp_rect
			(start 0.508 0.9398)
			(end -0.508 -0.9398)
			(stroke
				(width 0)
				(type default)
			)
			(fill no)
			(layer "B.Fab")
		)
		(pad "1" smd custom
			(at 0 -0.4445 90)
			(size 0.1397 0.1397)
			(layers "B.Cu" "B.Mask" "B.Paste")
			(net "P1V5_C")
			(options
				(clearance outline)
				(anchor circle)
			)
			(primitives
				(gr_poly
					(pts
						(arc
							(start -0.1778 0.2794)
							(mid -0.249642 0.249642)
							(end -0.2794 0.1778)
						)
						(arc
							(start -0.2794 -0.1778)
							(mid -0.249642 -0.249642)
							(end -0.1778 -0.2794)
						)
						(arc
							(start 0.1778 -0.2794)
							(mid 0.249642 -0.249642)
							(end 0.2794 -0.1778)
						)
						(arc
							(start 0.2794 0.1778)
							(mid 0.249642 0.249642)
							(end 0.1778 0.2794)
						)
					)
					(width 0)
					(fill yes)
				)
			)
		)
		(pad "2" smd custom
			(at 0 0.4445 90)
			(size 0.1397 0.1397)
			(layers "B.Cu" "B.Mask" "B.Paste")
			(net "GND")
			(options
				(clearance outline)
				(anchor circle)
			)
			(primitives
				(gr_poly
					(pts
						(arc
							(start -0.1778 0.2794)
							(mid -0.249642 0.249642)
							(end -0.2794 0.1778)
						)
						(arc
							(start -0.2794 -0.1778)
							(mid -0.249642 -0.249642)
							(end -0.1778 -0.2794)
						)
						(arc
							(start 0.1778 -0.2794)
							(mid 0.249642 -0.249642)
							(end 0.2794 -0.1778)
						)
						(arc
							(start 0.2794 0.1778)
							(mid 0.249642 0.249642)
							(end 0.1778 0.2794)
						)
					)
					(width 0)
					(fill yes)
				)
			)
		)
	)
	(footprint ""
		(layer "B.Cu")
		(at 171.532804 -20.88642)
		(property "Reference" "C318"
			(at 0 0 0)
			(layer "B.SilkS")
			(hide yes)
			(effects
				(font
					(size 1.27 1.27)
				)
				(justify mirror)
			)
		)
		(property "Value" "SCD22U10V1KX-GP"
			(at 2.8321 -1.7399 0)
			(unlocked yes)
			(layer "B.Fab")
			(hide yes)
			(effects
				(font
					(size 1.016 1.016)
					(thickness 0.1524)
				)
				(justify mirror)
			)
		)
		(property "Device Type" "C0201H13"
			(at 2.8321 -3.2639 0)
			(unlocked yes)
			(layer "B.Fab")
			(hide yes)
			(effects
				(font
					(size 1.016 1.016)
					(thickness 0.1524)
				)
				(justify mirror)
			)
		)
		(duplicate_pad_numbers_are_jumpers no)
		(fp_rect
			(start 0.2794 0.6477)
			(end -0.2794 -0.6477)
			(stroke
				(width 0)
				(type default)
			)
			(fill no)
			(layer "B.CrtYd")
		)
		(fp_rect
			(start 0.2794 0.6477)
			(end -0.2794 -0.6477)
			(stroke
				(width 0)
				(type default)
			)
			(fill no)
			(layer "B.Fab")
		)
		(pad "1" smd custom
			(at 0 -0.2794 180)
			(size 0.0762 0.0762)
			(layers "B.Cu" "B.Mask" "B.Paste")
			(net "PCIE_SCC_TO_COMP_C_3_DN")
			(options
				(clearance outline)
				(anchor circle)
			)
			(primitives
				(gr_poly
					(pts
						(arc
							(start 0.1524 0.127)
							(mid 0.137521 0.162921)
							(end 0.1016 0.1778)
						)
						(arc
							(start -0.1016 0.1778)
							(mid -0.137521 0.162921)
							(end -0.1524 0.127)
						)
						(arc
							(start -0.1524 -0.127)
							(mid -0.137521 -0.162921)
							(end -0.1016 -0.1778)
						)
						(arc
							(start 0.1016 -0.1778)
							(mid 0.137521 -0.162921)
							(end 0.1524 -0.127)
						)
					)
					(width 0)
					(fill yes)
				)
			)
		)
		(pad "2" smd custom
			(at 0 0.2794 180)
			(size 0.0762 0.0762)
			(layers "B.Cu" "B.Mask" "B.Paste")
			(net "PCIE_SCC_TO_COMP_3_DN")
			(options
				(clearance outline)
				(anchor circle)
			)
			(primitives
				(gr_poly
					(pts
						(arc
							(start 0.1524 0.127)
							(mid 0.137521 0.162921)
							(end 0.1016 0.1778)
						)
						(arc
							(start -0.1016 0.1778)
							(mid -0.137521 0.162921)
							(end -0.1524 0.127)
						)
						(arc
							(start -0.1524 -0.127)
							(mid -0.137521 -0.162921)
							(end -0.1016 -0.1778)
						)
						(arc
							(start 0.1016 -0.1778)
							(mid 0.137521 -0.162921)
							(end 0.1524 -0.127)
						)
					)
					(width 0)
					(fill yes)
				)
			)
		)
	)
)
